#ISCELL
  mstr_misc dns *
  *
#ISCELL
  pure_quanta quanta_title_block_c *
  *
#ISCELL
  standard offpage *
  page222_i1
#ISCELL
  logical_power universal_gnd *
  page222_i10
#CELL
  pure_quanta ltc4307cms8 *
  page222_i11
#CELL
  pure_quanta q_res *
  page222_i12
#CELL
  pure_quanta q_res *
  page222_i13
#ISCELL
  logical_power universal_gnd *
  page222_i14
#ISCELL
  logical_power universal_gnd *
  page222_i15
#CELL
  pure_quanta q_res *
  page222_i16
#CELL
  pure_quanta q_res *
  page222_i17
#CELL
  pure_quanta q_res *
  page222_i18
#CELL
  pure_quanta q_res *
  page222_i19
#ISCELL
  standard offpage *
  page222_i2
#CELL
  pure_quanta q_cap *
  page222_i20
#ISCELL
  logical_power universal_gnd *
  page222_i21
#ISCELL
  logical_power universal_power *
  page222_i22
#CELL
  pure_quanta q_res *
  page222_i23
#ISCELL
  logical_power universal_power *
  page222_i24
#CELL
  pure_quanta q_res *
  page222_i25
#CELL
  pure_quanta q_res *
  page222_i26
#CELL
  pure_quanta q_res *
  page222_i27
#ISCELL
  logical_power universal_gnd *
  page222_i28
#CELL
  pure_quanta q_res *
  page222_i29
#ISCELL
  standard offpage *
  page222_i3
#CELL
  pure_quanta q_res *
  page222_i30
#CELL
  pure_quanta ltc4307cms8 *
  page222_i31
#ISCELL
  logical_power universal_gnd *
  page222_i32
#CELL
  pure_quanta q_res *
  page222_i33
#CELL
  pure_quanta q_cap *
  page222_i34
#ISCELL
  logical_power universal_power *
  page222_i35
#ISCELL
  standard offpage *
  page222_i36
#ISCELL
  standard offpage *
  page222_i37
#CELL
  pure_quanta q_res *
  page222_i38
#ISCELL
  standard offpage *
  page222_i39
#ISCELL
  standard offpage *
  page222_i4
#ISCELL
  standard offpage *
  page222_i40
#ISCELL
  standard offpage *
  page222_i41
#CELL
  pure_quanta q_res *
  page222_i42
#CELL
  pure_quanta q_res *
  page222_i43
#CELL
  pure_quanta q_res *
  page222_i44
#ISCELL
  standard offpage *
  page222_i45
#ISCELL
  standard offpage *
  page222_i46
#ISCELL
  standard offpage *
  page222_i47
#CELL
  pure_quanta q_res *
  page222_i48
#ISCELL
  logical_power universal_gnd *
  page222_i49
#ISCELL
  standard offpage *
  page222_i5
#CELL
  pure_quanta ltc4307cms8 *
  page222_i50
#CELL
  pure_quanta q_res *
  page222_i51
#CELL
  pure_quanta q_res *
  page222_i52
#CELL
  pure_quanta q_res *
  page222_i53
#CELL
  pure_quanta q_res *
  page222_i54
#CELL
  pure_quanta q_res *
  page222_i55
#ISCELL
  logical_power universal_gnd *
  page222_i56
#ISCELL
  logical_power universal_power *
  page222_i57
#CELL
  pure_quanta q_cap *
  page222_i58
#CELL
  pure_quanta q_res *
  page222_i59
#ISCELL
  standard offpage *
  page222_i6
#ISCELL
  logical_power universal_power *
  page222_i60
#CELL
  pure_quanta q_res *
  page222_i61
#ISCELL
  logical_power universal_gnd *
  page222_i62
#CELL
  pure_quanta ltc4307cms8 *
  page222_i63
#CELL
  pure_quanta q_res *
  page222_i64
#CELL
  pure_quanta q_res *
  page222_i65
#CELL
  pure_quanta q_cap *
  page222_i66
#ISCELL
  logical_power universal_gnd *
  page222_i67
#ISCELL
  logical_power universal_power *
  page222_i68
#ISCELL
  standard offpage *
  page222_i69
#CELL
  pure_quanta q_res *
  page222_i7
#ISCELL
  standard offpage *
  page222_i70
#CELL
  pure_quanta q_res *
  page222_i71
#CELL
  pure_quanta q_res *
  page222_i72
#ISCELL
  standard offpage *
  page222_i73
#ISCELL
  standard offpage *
  page222_i74
#CELL
  pure_quanta q_res *
  page222_i75
#ISCELL
  logical_power universal_power *
  page222_i76
#CELL
  pure_quanta q_res *
  page222_i77
#CELL
  pure_quanta q_res *
  page222_i78
#CELL
  pure_quanta q_res *
  page222_i79
#CELL
  pure_quanta q_res *
  page222_i8
#CELL
  pure_quanta q_res *
  page222_i80
#CELL
  pure_quanta q_res *
  page222_i81
#ISCELL
  logical_power universal_power *
  page222_i82
#ISCELL
  standard offpage *
  page222_i83
#ISCELL
  standard offpage *
  page222_i84
#CELL
  pure_quanta q_res *
  page222_i9
